G04*
G04 #@! TF.GenerationSoftware,Altium Limited,Altium Designer,22.4.2 (48)*
G04*
G04 Layer_Physical_Order=2*
G04 Layer_Color=65280*
%FSLAX25Y25*%
%MOIN*%
G70*
G04*
G04 #@! TF.SameCoordinates,B69760C6-9901-4916-8BAC-4CFDAA04743E*
G04*
G04*
G04 #@! TF.FilePolarity,Positive*
G04*
G01*
G75*
%ADD13C,0.02000*%
%ADD55C,0.00800*%
%ADD58C,0.02400*%
G36*
X260531Y123977D02*
X261155Y123852D01*
X261743Y123609D01*
X262272Y123256D01*
X262722Y122806D01*
X263076Y122277D01*
X263320Y121689D01*
X263445Y121065D01*
X263445Y120747D01*
X263433Y3996D01*
X263433Y3996D01*
X263433Y3996D01*
X263433Y3701D01*
X263318Y3124D01*
X263093Y2579D01*
X262766Y2090D01*
X262350Y1673D01*
X261860Y1345D01*
X261316Y1120D01*
X260738Y1004D01*
X260444Y1004D01*
X4114Y1020D01*
X4114Y1020D01*
X4114Y1020D01*
X3809D01*
X3212Y1139D01*
X2648Y1372D01*
X2142Y1710D01*
X1710Y2142D01*
X1372Y2648D01*
X1139Y3212D01*
X1020Y3809D01*
Y4114D01*
X1020Y4114D01*
X1020Y4114D01*
X1012Y120772D01*
X1012Y121086D01*
X1134Y121704D01*
X1375Y122285D01*
X1725Y122809D01*
X2169Y123254D01*
X2692Y123604D01*
X3274Y123845D01*
X3891Y123968D01*
X4206Y123969D01*
X260213Y123977D01*
X260531Y123977D01*
D02*
G37*
%LPC*%
G36*
X250014Y120886D02*
X248812D01*
X248714Y120866D01*
X248613D01*
X247434Y120632D01*
X247342Y120593D01*
X247243Y120574D01*
X246133Y120114D01*
X246049Y120058D01*
X245956Y120019D01*
X244957Y119351D01*
X244886Y119281D01*
X244802Y119225D01*
X243952Y118375D01*
X243897Y118291D01*
X243826Y118220D01*
X243158Y117221D01*
X243119Y117128D01*
X243064Y117044D01*
X242604Y115934D01*
X242584Y115835D01*
X242546Y115743D01*
X242311Y114564D01*
Y114463D01*
X242291Y114365D01*
Y113163D01*
X242311Y113064D01*
Y112964D01*
X242546Y111785D01*
X242584Y111692D01*
X242604Y111594D01*
X243064Y110483D01*
X243119Y110399D01*
X243158Y110307D01*
X243826Y109307D01*
X243897Y109236D01*
X243952Y109153D01*
X244802Y108303D01*
X244886Y108247D01*
X244957Y108176D01*
X245956Y107508D01*
X246049Y107470D01*
X246133Y107414D01*
X247243Y106954D01*
X247342Y106934D01*
X247434Y106896D01*
X248613Y106661D01*
X248714D01*
X248812Y106642D01*
X250014D01*
X250113Y106661D01*
X250213D01*
X251392Y106896D01*
X251485Y106934D01*
X251584Y106954D01*
X252694Y107414D01*
X252778Y107470D01*
X252870Y107508D01*
X253870Y108176D01*
X253941Y108247D01*
X254024Y108303D01*
X254874Y109153D01*
X254930Y109236D01*
X255001Y109307D01*
X255669Y110307D01*
X255707Y110399D01*
X255763Y110483D01*
X256223Y111594D01*
X256243Y111692D01*
X256281Y111785D01*
X256516Y112964D01*
Y113064D01*
X256535Y113163D01*
Y114365D01*
X256516Y114463D01*
Y114564D01*
X256281Y115743D01*
X256243Y115835D01*
X256223Y115934D01*
X255763Y117044D01*
X255707Y117128D01*
X255669Y117221D01*
X255001Y118220D01*
X254930Y118291D01*
X254874Y118375D01*
X254024Y119225D01*
X253941Y119281D01*
X253870Y119351D01*
X252870Y120019D01*
X252778Y120058D01*
X252694Y120114D01*
X251584Y120574D01*
X251485Y120593D01*
X251392Y120632D01*
X250213Y120866D01*
X250113D01*
X250014Y120886D01*
D02*
G37*
G36*
X11825D02*
X10623D01*
X10525Y120866D01*
X10424D01*
X9245Y120632D01*
X9153Y120593D01*
X9054Y120574D01*
X7944Y120114D01*
X7860Y120058D01*
X7767Y120019D01*
X6768Y119351D01*
X6697Y119281D01*
X6613Y119225D01*
X5763Y118375D01*
X5708Y118291D01*
X5637Y118220D01*
X4969Y117221D01*
X4930Y117128D01*
X4875Y117044D01*
X4415Y115934D01*
X4395Y115835D01*
X4357Y115743D01*
X4122Y114564D01*
Y114463D01*
X4103Y114365D01*
Y113163D01*
X4122Y113064D01*
Y112964D01*
X4357Y111785D01*
X4395Y111692D01*
X4415Y111594D01*
X4875Y110483D01*
X4930Y110399D01*
X4969Y110307D01*
X5637Y109307D01*
X5708Y109236D01*
X5763Y109153D01*
X6613Y108303D01*
X6697Y108247D01*
X6768Y108176D01*
X7767Y107508D01*
X7860Y107470D01*
X7944Y107414D01*
X9054Y106954D01*
X9153Y106934D01*
X9245Y106896D01*
X10424Y106661D01*
X10525D01*
X10623Y106642D01*
X11825D01*
X11924Y106661D01*
X12024D01*
X13203Y106896D01*
X13296Y106934D01*
X13395Y106954D01*
X14505Y107414D01*
X14589Y107470D01*
X14681Y107508D01*
X15681Y108176D01*
X15752Y108247D01*
X15835Y108303D01*
X16685Y109153D01*
X16741Y109236D01*
X16812Y109307D01*
X17480Y110307D01*
X17518Y110399D01*
X17574Y110483D01*
X18034Y111594D01*
X18054Y111692D01*
X18092Y111785D01*
X18327Y112964D01*
Y113064D01*
X18346Y113163D01*
Y114365D01*
X18327Y114463D01*
Y114564D01*
X18092Y115743D01*
X18054Y115835D01*
X18034Y115934D01*
X17574Y117044D01*
X17518Y117128D01*
X17480Y117221D01*
X16812Y118220D01*
X16741Y118291D01*
X16685Y118375D01*
X15835Y119225D01*
X15752Y119281D01*
X15681Y119351D01*
X14681Y120019D01*
X14589Y120058D01*
X14505Y120114D01*
X13395Y120574D01*
X13296Y120593D01*
X13203Y120632D01*
X12024Y120866D01*
X11924D01*
X11825Y120886D01*
D02*
G37*
G36*
X138058Y113000D02*
X137342D01*
X136680Y112726D01*
X136174Y112220D01*
X135900Y111558D01*
Y110842D01*
X136174Y110180D01*
X136680Y109674D01*
X136680Y109674D01*
Y105726D01*
X136680Y105726D01*
X136174Y105220D01*
X135900Y104558D01*
Y103842D01*
X136174Y103180D01*
X136680Y102674D01*
X137342Y102400D01*
X138058D01*
X138720Y102674D01*
X139226Y103180D01*
X139500Y103842D01*
Y104558D01*
X139226Y105220D01*
X138720Y105726D01*
X138720Y105726D01*
Y109674D01*
X138720Y109674D01*
X139226Y110180D01*
X139500Y110842D01*
Y111558D01*
X139226Y112220D01*
X138720Y112726D01*
X138058Y113000D01*
D02*
G37*
G36*
X121558Y108500D02*
X120842D01*
X120180Y108226D01*
X119674Y107720D01*
X119400Y107058D01*
Y106342D01*
X119674Y105680D01*
X120180Y105174D01*
X120180Y105174D01*
Y103795D01*
X120180Y103795D01*
X119674Y103288D01*
X119400Y102627D01*
Y101910D01*
X119674Y101249D01*
X120180Y100743D01*
X120842Y100469D01*
X121558D01*
X122220Y100743D01*
X122726Y101249D01*
X123000Y101910D01*
Y102627D01*
X122726Y103288D01*
X122220Y103795D01*
X122220Y103795D01*
Y105174D01*
X122220Y105174D01*
X122726Y105680D01*
X123000Y106342D01*
Y107058D01*
X122726Y107720D01*
X122220Y108226D01*
X121558Y108500D01*
D02*
G37*
G36*
X217758Y81800D02*
X217042D01*
X216380Y81526D01*
X215874Y81020D01*
X215600Y80358D01*
Y79642D01*
X215769Y79235D01*
Y73731D01*
X209365D01*
X208958Y73900D01*
X208242D01*
X207580Y73626D01*
X207074Y73120D01*
X206800Y72458D01*
Y71742D01*
X207074Y71080D01*
X207580Y70574D01*
X208242Y70300D01*
X208958D01*
X209365Y70469D01*
X216435D01*
X216842Y70300D01*
X217558D01*
X218220Y70574D01*
X218726Y71080D01*
X219000Y71742D01*
Y72251D01*
X219031Y72408D01*
Y79235D01*
X219200Y79642D01*
Y80358D01*
X218926Y81020D01*
X218420Y81526D01*
X217758Y81800D01*
D02*
G37*
G36*
X198658Y67600D02*
X197942D01*
X197535Y67431D01*
X188237D01*
X188119Y67408D01*
X187780D01*
X187558Y67500D01*
X186842D01*
X186180Y67226D01*
X185674Y66720D01*
X185400Y66058D01*
Y65342D01*
X185674Y64680D01*
X186180Y64174D01*
X186842Y63900D01*
X187558D01*
X188150Y64145D01*
X188213D01*
X188331Y64169D01*
X197535D01*
X197942Y64000D01*
X198658D01*
X199320Y64274D01*
X199826Y64780D01*
X200100Y65442D01*
Y66158D01*
X199826Y66820D01*
X199320Y67326D01*
X198658Y67600D01*
D02*
G37*
G36*
X69858Y68100D02*
X69142D01*
X68480Y67826D01*
X67974Y67320D01*
X67974Y67320D01*
X57800D01*
X57410Y67242D01*
X57079Y67021D01*
X55158Y65100D01*
X55158Y65100D01*
X54442D01*
X53780Y64826D01*
X53274Y64320D01*
X53000Y63658D01*
Y62942D01*
X53274Y62280D01*
X53780Y61774D01*
X54442Y61500D01*
X55158D01*
X55820Y61774D01*
X56326Y62280D01*
X56600Y62942D01*
Y63658D01*
X56600Y63658D01*
X58222Y65280D01*
X67974D01*
X67974Y65280D01*
X68480Y64774D01*
X69142Y64500D01*
X69858D01*
X70520Y64774D01*
X71026Y65280D01*
X71300Y65942D01*
Y66658D01*
X71026Y67320D01*
X70520Y67826D01*
X69858Y68100D01*
D02*
G37*
G36*
X68258Y60800D02*
X67542D01*
X66880Y60526D01*
X66374Y60020D01*
X66374Y60020D01*
X61989D01*
X61599Y59942D01*
X61268Y59721D01*
X55879Y54332D01*
X55658Y54001D01*
X55580Y53611D01*
Y50526D01*
X55580Y50526D01*
X55074Y50020D01*
X54800Y49358D01*
Y48642D01*
X55074Y47980D01*
X55580Y47474D01*
X56242Y47200D01*
X56958D01*
X57620Y47474D01*
X58126Y47980D01*
X58400Y48642D01*
Y49358D01*
X58126Y50020D01*
X57620Y50526D01*
X57620Y50526D01*
Y53189D01*
X60551Y56120D01*
X61141Y56003D01*
X61274Y55680D01*
X61780Y55174D01*
X62442Y54900D01*
X63158D01*
X63158Y54900D01*
X63966Y54092D01*
X63761Y53597D01*
Y52881D01*
X64035Y52219D01*
X64542Y51713D01*
X65203Y51439D01*
X65919D01*
X66581Y51713D01*
X67087Y52219D01*
X67361Y52881D01*
Y53597D01*
X67087Y54258D01*
X66581Y54765D01*
X65919Y55039D01*
X65903D01*
X64600Y56342D01*
X64600Y56342D01*
Y57058D01*
X64425Y57480D01*
X64719Y57980D01*
X66374D01*
X66374Y57980D01*
X66880Y57474D01*
X67542Y57200D01*
X68258D01*
X68920Y57474D01*
X69426Y57980D01*
X69700Y58642D01*
Y59358D01*
X69426Y60020D01*
X68920Y60526D01*
X68258Y60800D01*
D02*
G37*
G36*
X225458Y63000D02*
X224742D01*
X224080Y62726D01*
X223574Y62220D01*
X223300Y61558D01*
Y60842D01*
X223574Y60180D01*
X224080Y59674D01*
X224080Y59674D01*
Y43922D01*
X222458Y42300D01*
X222458Y42300D01*
X221742D01*
X221080Y42026D01*
X220574Y41520D01*
X220300Y40858D01*
Y40142D01*
X220574Y39480D01*
X221080Y38974D01*
X221742Y38700D01*
X222458D01*
X223120Y38974D01*
X223626Y39480D01*
X223900Y40142D01*
Y40858D01*
X223900Y40858D01*
X225821Y42779D01*
X226042Y43110D01*
X226120Y43500D01*
Y59674D01*
X226120Y59674D01*
X226626Y60180D01*
X226900Y60842D01*
Y61558D01*
X226626Y62220D01*
X226120Y62726D01*
X225458Y63000D01*
D02*
G37*
G36*
X207875Y45228D02*
X207159D01*
X206498Y44954D01*
X205991Y44447D01*
X205717Y43786D01*
Y43069D01*
X205886Y42662D01*
Y33582D01*
X205717Y33175D01*
Y32459D01*
X205991Y31798D01*
X206498Y31291D01*
X207159Y31017D01*
X207875D01*
X208537Y31291D01*
X209043Y31798D01*
X209317Y32459D01*
Y33175D01*
X209149Y33582D01*
Y42662D01*
X209317Y43069D01*
Y43786D01*
X209043Y44447D01*
X208537Y44954D01*
X207875Y45228D01*
D02*
G37*
G36*
X250014Y18523D02*
X248812D01*
X248714Y18504D01*
X248613D01*
X247434Y18269D01*
X247342Y18231D01*
X247243Y18211D01*
X246133Y17751D01*
X246049Y17696D01*
X245956Y17657D01*
X244957Y16989D01*
X244886Y16918D01*
X244802Y16862D01*
X243952Y16013D01*
X243897Y15929D01*
X243826Y15858D01*
X243158Y14859D01*
X243119Y14766D01*
X243064Y14682D01*
X242604Y13572D01*
X242584Y13473D01*
X242546Y13381D01*
X242311Y12201D01*
Y12101D01*
X242291Y12003D01*
Y10801D01*
X242311Y10702D01*
Y10602D01*
X242546Y9423D01*
X242584Y9330D01*
X242604Y9231D01*
X243064Y8121D01*
X243119Y8037D01*
X243158Y7945D01*
X243826Y6945D01*
X243897Y6874D01*
X243952Y6791D01*
X244802Y5941D01*
X244886Y5885D01*
X244957Y5814D01*
X245956Y5146D01*
X246049Y5108D01*
X246133Y5052D01*
X247243Y4592D01*
X247342Y4572D01*
X247434Y4534D01*
X248613Y4299D01*
X248714D01*
X248812Y4280D01*
X250014D01*
X250113Y4299D01*
X250213D01*
X251392Y4534D01*
X251485Y4572D01*
X251584Y4592D01*
X252694Y5052D01*
X252778Y5108D01*
X252870Y5146D01*
X253870Y5814D01*
X253941Y5885D01*
X254024Y5941D01*
X254874Y6791D01*
X254930Y6874D01*
X255001Y6945D01*
X255669Y7945D01*
X255707Y8037D01*
X255763Y8121D01*
X256223Y9231D01*
X256243Y9330D01*
X256281Y9423D01*
X256516Y10602D01*
Y10702D01*
X256535Y10801D01*
Y12003D01*
X256516Y12101D01*
Y12201D01*
X256281Y13381D01*
X256243Y13473D01*
X256223Y13572D01*
X255763Y14682D01*
X255707Y14766D01*
X255669Y14859D01*
X255001Y15858D01*
X254930Y15929D01*
X254874Y16013D01*
X254024Y16862D01*
X253941Y16918D01*
X253870Y16989D01*
X252870Y17657D01*
X252778Y17696D01*
X252694Y17751D01*
X251584Y18211D01*
X251485Y18231D01*
X251392Y18269D01*
X250213Y18504D01*
X250113D01*
X250014Y18523D01*
D02*
G37*
G36*
X11825D02*
X10623D01*
X10525Y18504D01*
X10424D01*
X9245Y18269D01*
X9153Y18231D01*
X9054Y18211D01*
X7944Y17751D01*
X7860Y17696D01*
X7767Y17657D01*
X6768Y16989D01*
X6697Y16918D01*
X6613Y16862D01*
X5763Y16013D01*
X5708Y15929D01*
X5637Y15858D01*
X4969Y14859D01*
X4930Y14766D01*
X4875Y14682D01*
X4415Y13572D01*
X4395Y13473D01*
X4357Y13381D01*
X4122Y12201D01*
Y12101D01*
X4103Y12003D01*
Y10801D01*
X4122Y10702D01*
Y10602D01*
X4357Y9423D01*
X4395Y9330D01*
X4415Y9231D01*
X4875Y8121D01*
X4930Y8037D01*
X4969Y7945D01*
X5637Y6945D01*
X5708Y6874D01*
X5763Y6791D01*
X6613Y5941D01*
X6697Y5885D01*
X6768Y5814D01*
X7767Y5146D01*
X7860Y5108D01*
X7944Y5052D01*
X9054Y4592D01*
X9153Y4572D01*
X9245Y4534D01*
X10424Y4299D01*
X10525D01*
X10623Y4280D01*
X11825D01*
X11924Y4299D01*
X12024D01*
X13203Y4534D01*
X13296Y4572D01*
X13395Y4592D01*
X14505Y5052D01*
X14589Y5108D01*
X14681Y5146D01*
X15681Y5814D01*
X15752Y5885D01*
X15835Y5941D01*
X16685Y6791D01*
X16741Y6874D01*
X16812Y6945D01*
X17480Y7945D01*
X17518Y8037D01*
X17574Y8121D01*
X18034Y9231D01*
X18054Y9330D01*
X18092Y9423D01*
X18327Y10602D01*
Y10702D01*
X18346Y10801D01*
Y12003D01*
X18327Y12101D01*
Y12201D01*
X18092Y13381D01*
X18054Y13473D01*
X18034Y13572D01*
X17574Y14682D01*
X17518Y14766D01*
X17480Y14859D01*
X16812Y15858D01*
X16741Y15929D01*
X16685Y16013D01*
X15835Y16862D01*
X15752Y16918D01*
X15681Y16989D01*
X14681Y17657D01*
X14589Y17696D01*
X14505Y17751D01*
X13395Y18211D01*
X13296Y18231D01*
X13203Y18269D01*
X12024Y18504D01*
X11924D01*
X11825Y18523D01*
D02*
G37*
%LPD*%
D13*
X188237Y65800D02*
X198300D01*
X187276Y65776D02*
X188213D01*
X188237Y65800D01*
X187200Y65700D02*
X187276Y65776D01*
X208600Y72100D02*
X217200D01*
Y72208D02*
X217400Y72408D01*
X217200Y72100D02*
Y72208D01*
X217400Y72408D02*
Y80000D01*
X207517Y32817D02*
Y43428D01*
D55*
X222100Y40500D02*
X225100Y43500D01*
Y61200D01*
X61989Y59000D02*
X67900D01*
X56600Y49000D02*
Y53611D01*
X61989Y59000D01*
X54800Y63300D02*
X57800Y66300D01*
X69500D01*
X62800Y56700D02*
X65255Y54245D01*
Y53545D02*
Y54245D01*
Y53545D02*
X65561Y53239D01*
X137700Y104200D02*
Y111200D01*
X121200Y102269D02*
Y106700D01*
D58*
X215400Y47200D02*
D03*
X198300Y65800D02*
D03*
X187200Y65700D02*
D03*
X75800Y74400D02*
D03*
X87968Y80005D02*
D03*
X83568D02*
D03*
X79232Y80753D02*
D03*
X80035Y74573D02*
D03*
X84391Y75195D02*
D03*
X88791D02*
D03*
X18874Y81741D02*
D03*
X17342Y77617D02*
D03*
X19368Y73711D02*
D03*
X23616Y72562D02*
D03*
X27335Y74913D02*
D03*
X31689Y75547D02*
D03*
X36089D02*
D03*
X40202Y73983D02*
D03*
X47600Y75200D02*
D03*
X56960Y75547D02*
D03*
X61360D02*
D03*
X65760D02*
D03*
X70160D02*
D03*
X75868Y80753D02*
D03*
X71486Y80358D02*
D03*
X67086D02*
D03*
X62686D02*
D03*
X58286D02*
D03*
X53886D02*
D03*
X49486D02*
D03*
X45088Y80484D02*
D03*
X40689Y80358D02*
D03*
X36289D02*
D03*
X31889D02*
D03*
X27503Y80696D02*
D03*
X23955Y83298D02*
D03*
X108600Y37300D02*
D03*
X116925D02*
D03*
X125250D02*
D03*
X133575D02*
D03*
X141900D02*
D03*
X108700Y29000D02*
D03*
X117025D02*
D03*
X125350D02*
D03*
X133675D02*
D03*
X142000D02*
D03*
X108700Y45700D02*
D03*
X117025D02*
D03*
X125350D02*
D03*
X133675D02*
D03*
X142000D02*
D03*
X108700Y54100D02*
D03*
X117025D02*
D03*
X125350D02*
D03*
X133675D02*
D03*
X142000D02*
D03*
X108600Y62100D02*
D03*
X116925D02*
D03*
X125250D02*
D03*
X133575D02*
D03*
X141900D02*
D03*
X108600Y70400D02*
D03*
X116925D02*
D03*
X125250D02*
D03*
X133575D02*
D03*
X141900D02*
D03*
Y78800D02*
D03*
X133575D02*
D03*
X125250D02*
D03*
X116925D02*
D03*
X108600D02*
D03*
X259467Y120459D02*
D03*
Y110459D02*
D03*
Y100459D02*
D03*
Y90459D02*
D03*
Y80459D02*
D03*
Y70459D02*
D03*
Y60459D02*
D03*
Y50459D02*
D03*
Y40459D02*
D03*
Y30459D02*
D03*
Y20459D02*
D03*
Y10459D02*
D03*
X249467Y100459D02*
D03*
Y90459D02*
D03*
Y20459D02*
D03*
X239467Y120459D02*
D03*
Y110459D02*
D03*
Y100459D02*
D03*
Y90459D02*
D03*
Y60459D02*
D03*
Y50459D02*
D03*
Y20459D02*
D03*
Y10459D02*
D03*
X229467Y120459D02*
D03*
Y110459D02*
D03*
Y100459D02*
D03*
Y90459D02*
D03*
Y80459D02*
D03*
Y70459D02*
D03*
Y60459D02*
D03*
Y10459D02*
D03*
X219467Y120459D02*
D03*
Y110459D02*
D03*
Y100459D02*
D03*
Y90459D02*
D03*
X209467Y120459D02*
D03*
Y110459D02*
D03*
Y100459D02*
D03*
Y60459D02*
D03*
X199467Y120459D02*
D03*
Y110459D02*
D03*
Y80459D02*
D03*
Y30459D02*
D03*
X189467Y120459D02*
D03*
Y90459D02*
D03*
Y80459D02*
D03*
Y60459D02*
D03*
Y50459D02*
D03*
Y40459D02*
D03*
Y30459D02*
D03*
Y10459D02*
D03*
X179467Y120459D02*
D03*
Y90459D02*
D03*
Y60459D02*
D03*
Y50459D02*
D03*
Y40459D02*
D03*
Y20459D02*
D03*
X169467Y120459D02*
D03*
Y80459D02*
D03*
Y60459D02*
D03*
Y50459D02*
D03*
Y30459D02*
D03*
Y20459D02*
D03*
X159467Y120459D02*
D03*
Y90459D02*
D03*
Y80459D02*
D03*
Y70459D02*
D03*
Y40459D02*
D03*
Y30459D02*
D03*
Y20459D02*
D03*
X149467Y120459D02*
D03*
Y20459D02*
D03*
X139467Y120459D02*
D03*
Y20459D02*
D03*
X129467Y120459D02*
D03*
Y20459D02*
D03*
X119467Y120459D02*
D03*
Y110459D02*
D03*
Y20459D02*
D03*
X109467Y120459D02*
D03*
Y20459D02*
D03*
X99467Y120459D02*
D03*
Y110459D02*
D03*
Y20459D02*
D03*
X89467Y120459D02*
D03*
Y110459D02*
D03*
Y100459D02*
D03*
Y90459D02*
D03*
Y50459D02*
D03*
Y40459D02*
D03*
Y30459D02*
D03*
Y10459D02*
D03*
X79467Y120459D02*
D03*
Y110459D02*
D03*
Y100459D02*
D03*
Y90459D02*
D03*
Y20459D02*
D03*
Y10459D02*
D03*
X69467Y120459D02*
D03*
Y110459D02*
D03*
Y100459D02*
D03*
Y90459D02*
D03*
Y50459D02*
D03*
Y40459D02*
D03*
Y20459D02*
D03*
X59467Y120459D02*
D03*
Y110459D02*
D03*
Y100459D02*
D03*
Y90459D02*
D03*
Y10459D02*
D03*
X49467Y120459D02*
D03*
Y110459D02*
D03*
Y100459D02*
D03*
Y90459D02*
D03*
Y40459D02*
D03*
Y30459D02*
D03*
Y20459D02*
D03*
Y10459D02*
D03*
X39467Y120459D02*
D03*
Y110459D02*
D03*
Y100459D02*
D03*
Y90459D02*
D03*
Y70459D02*
D03*
Y60459D02*
D03*
Y50459D02*
D03*
Y40459D02*
D03*
Y30459D02*
D03*
Y20459D02*
D03*
Y10459D02*
D03*
X29467Y120459D02*
D03*
Y110459D02*
D03*
Y100459D02*
D03*
Y70459D02*
D03*
Y60459D02*
D03*
Y50459D02*
D03*
Y40459D02*
D03*
Y30459D02*
D03*
Y20459D02*
D03*
Y10459D02*
D03*
X19467Y120459D02*
D03*
Y110459D02*
D03*
Y100459D02*
D03*
Y60459D02*
D03*
Y50459D02*
D03*
Y40459D02*
D03*
Y30459D02*
D03*
Y20459D02*
D03*
X9467Y100459D02*
D03*
Y90459D02*
D03*
Y80459D02*
D03*
Y70459D02*
D03*
Y60459D02*
D03*
Y50459D02*
D03*
Y40459D02*
D03*
Y30459D02*
D03*
Y20459D02*
D03*
X193900Y56000D02*
D03*
X225100Y61200D02*
D03*
X67900Y59000D02*
D03*
X56600Y49000D02*
D03*
X62800Y56700D02*
D03*
X65561Y53239D02*
D03*
X54800Y63300D02*
D03*
X69500Y66300D02*
D03*
X208600Y72100D02*
D03*
X137700Y104200D02*
D03*
Y111200D02*
D03*
X217400Y80000D02*
D03*
X121200Y102269D02*
D03*
Y106700D02*
D03*
X207517Y32817D02*
D03*
X217200Y72100D02*
D03*
X207517Y43428D02*
D03*
X222100Y40500D02*
D03*
M02*
